(kicad_pcb
	(version 20241229)
	(generator "pcbnew")
	(generator_version "9.0")
	(general
		(thickness 1.61)
		(legacy_teardrops no)
	)
	(paper "A3")
	(title_block
		(title "RDIMM DDR5 Tester")
		(date "2026-05-21")
		(rev "2.2.0")
		(company "Antmicro")
		(comment 9 "footprint 119 of 796 (U34), pads 266-329 of 676")
	)
	(layers
		(0 "F.Cu" signal)
		(4 "In1.Cu" power)
		(6 "In2.Cu" mixed)
		(8 "In3.Cu" power)
		(10 "In4.Cu" mixed)
		(12 "In5.Cu" power)
		(14 "In6.Cu" mixed)
		(16 "In7.Cu" power)
		(18 "In8.Cu" power)
		(20 "In9.Cu" mixed)
		(22 "In10.Cu" power)
		(2 "B.Cu" signal)
		(9 "F.Adhes" user "F.Adhesive")
		(11 "B.Adhes" user "B.Adhesive")
		(13 "F.Paste" user)
		(15 "B.Paste" user)
		(5 "F.SilkS" user "F.Silkscreen")
		(7 "B.SilkS" user "B.Silkscreen")
		(1 "F.Mask" user)
		(3 "B.Mask" user)
		(17 "Dwgs.User" user "User.Drawings")
		(19 "Cmts.User" user "User.Comments")
		(21 "Eco1.User" user "User.Eco1")
		(23 "Eco2.User" user "User.Eco2")
		(25 "Edge.Cuts" user)
		(27 "Margin" user)
		(31 "F.CrtYd" user "F.Courtyard")
		(29 "B.CrtYd" user "B.Courtyard")
		(35 "F.Fab" user)
		(33 "B.Fab" user)
	)
	(footprint "antmicro-footprints:BGA-676_27x27mm_Layout26x26_P1x1mm_FFVB676"
		(layer "F.Cu")
		(at 188.5 152.5 90)
		(property "Reference" "U34"
			(at -14.72 12.46 180)
			(layer "F.SilkS")
			(effects
				(font
					(size 0.7 0.7)
					(thickness 0.15)
				)
				(justify left bottom)
			)
		)
		(property "Value" "XCAU25P-2FFVB676I"
			(at 0 15.5 90)
			(layer "F.Fab")
			(effects
				(font
					(size 0.7 0.7)
					(thickness 0.15)
				)
				(justify left bottom)
			)
		)
		(property "Datasheet" "https://docs.xilinx.com/viewer/book-attachment/2PXOpPtpaABIt0fkzeBLnw/hvbsEUaOT0OxFhln7VEVyA"
			(at 0 0 90)
			(layer "F.Fab")
			(hide yes)
			(effects
				(font
					(size 1.27 1.27)
					(thickness 0.15)
				)
			)
		)
		(property "MPN" "XCAU25P-2FFVB676I"
			(at 0 0 90)
			(unlocked yes)
			(layer "F.Fab")
			(hide yes)
			(effects
				(font
					(size 1 1)
					(thickness 0.15)
				)
			)
		)
		(property "Manufacturer" "AMD-Xilinx"
			(at 0 0 90)
			(unlocked yes)
			(layer "F.Fab")
			(hide yes)
			(effects
				(font
					(size 1 1)
					(thickness 0.15)
				)
			)
		)
		(property "Author" "Antmicro"
			(at 0 0 90)
			(unlocked yes)
			(layer "F.Fab")
			(hide yes)
			(effects
				(font
					(size 1 1)
					(thickness 0.15)
				)
			)
		)
		(property "License" "Apache-2.0"
			(at 0 0 90)
			(unlocked yes)
			(layer "F.Fab")
			(hide yes)
			(effects
				(font
					(size 1 1)
					(thickness 0.15)
				)
			)
		)
		(sheetname "/FPGA Config/")
		(sheetfile "fpga-config.kicad_sch")
		(attr smd)
		(pad "E6" smd circle
			(at -7.5 -8.5 90)
			(size 0.5 0.5)
			(layers "F.Cu" "F.Mask" "F.Paste")
			(net 1 "GND")
			(pinfunction "GND")
			(pintype "passive")
			(solder_mask_margin 0.075)
		)
		(pad "E7" smd circle
			(at -6.5 -8.5 90)
			(size 0.5 0.5)
			(layers "F.Cu" "F.Mask" "F.Paste")
			(net 172 "+1V2_MGTAVTT")
			(pinfunction "MGTAVTT_R")
			(pintype "passive")
			(solder_mask_margin 0.075)
		)
		(pad "E8" smd circle
			(at -5.5 -8.5 90)
			(size 0.5 0.5)
			(layers "F.Cu" "F.Mask" "F.Paste")
			(net 1 "GND")
			(pinfunction "GND")
			(pintype "passive")
			(solder_mask_margin 0.075)
		)
		(pad "E9" smd circle
			(at -4.5 -8.5 90)
			(size 0.5 0.5)
			(layers "F.Cu" "F.Mask" "F.Paste")
			(net 151 "+3V3")
			(pinfunction "VCCO_86")
			(pintype "power_in")
			(solder_mask_margin 0.075)
		)
		(pad "E10" smd circle
			(at -3.5 -8.5 90)
			(size 0.5 0.5)
			(layers "F.Cu" "F.Mask" "F.Paste")
			(net 518 "unconnected-(U34G-IO_L7N_HDGC_AD5N_86-PadE10)")
			(pinfunction "IO_L7N_HDGC_AD5N_86")
			(pintype "bidirectional+no_connect")
			(die_length 15.887)
			(solder_mask_margin 0.075)
		)
		(pad "E11" smd circle
			(at -2.5 -8.5 90)
			(size 0.5 0.5)
			(layers "F.Cu" "F.Mask" "F.Paste")
			(net 519 "unconnected-(U34G-IO_L7P_HDGC_AD5P_86-PadE11)")
			(pinfunction "IO_L7P_HDGC_AD5P_86")
			(pintype "bidirectional+no_connect")
			(die_length 15.718)
			(solder_mask_margin 0.075)
		)
		(pad "E12" smd circle
			(at -1.5 -8.5 90)
			(size 0.5 0.5)
			(layers "F.Cu" "F.Mask" "F.Paste")
			(net 520 "unconnected-(U34H-IO_L7N_HDGC_87-PadE12)")
			(pinfunction "IO_L7N_HDGC_87")
			(pintype "bidirectional+no_connect")
			(die_length 13.416)
			(solder_mask_margin 0.075)
		)
		(pad "E13" smd circle
			(at -0.5 -8.5 90)
			(size 0.5 0.5)
			(layers "F.Cu" "F.Mask" "F.Paste")
			(net 779 "~{I3C_EXT_PU}")
			(pinfunction "IO_L7P_HDGC_87")
			(pintype "bidirectional")
			(die_length 13.324)
			(solder_mask_margin 0.075)
		)
		(pad "E14" smd circle
			(at 0.5 -8.5 90)
			(size 0.5 0.5)
			(layers "F.Cu" "F.Mask" "F.Paste")
			(net 151 "+3V3")
			(pinfunction "VCCO_87")
			(pintype "power_in")
			(solder_mask_margin 0.075)
		)
		(pad "E15" smd circle
			(at 1.5 -8.5 90)
			(size 0.5 0.5)
			(layers "F.Cu" "F.Mask" "F.Paste")
			(net 615 "/FPGA banks HP/HyperRAM.DQ2")
			(pinfunction "IO_L3P_T0L_N4_AD15P_67")
			(pintype "bidirectional")
			(die_length 15.891)
			(solder_mask_margin 0.075)
		)
		(pad "E16" smd circle
			(at 2.5 -8.5 90)
			(size 0.5 0.5)
			(layers "F.Cu" "F.Mask" "F.Paste")
			(net 616 "/FPGA banks HP/HyperRAM.CK_P")
			(pinfunction "IO_L4P_T0U_N6_DBC_AD7P_67")
			(pintype "bidirectional")
			(die_length 15.758)
			(solder_mask_margin 0.075)
		)
		(pad "E17" smd circle
			(at 3.5 -8.5 90)
			(size 0.5 0.5)
			(layers "F.Cu" "F.Mask" "F.Paste")
			(net 617 "/FPGA banks HP/HyperRAM.CK_N")
			(pinfunction "IO_L4N_T0U_N7_DBC_AD7N_67")
			(pintype "bidirectional")
			(die_length 15.815)
			(solder_mask_margin 0.075)
		)
		(pad "E18" smd circle
			(at 4.5 -8.5 90)
			(size 0.5 0.5)
			(layers "F.Cu" "F.Mask" "F.Paste")
			(net 646 "unconnected-(U34E-IO_L11P_T1U_N8_GC_67-PadE18)")
			(pinfunction "IO_L11P_T1U_N8_GC_67")
			(pintype "bidirectional+no_connect")
			(die_length 12.991)
			(solder_mask_margin 0.075)
		)
		(pad "E19" smd circle
			(at 5.5 -8.5 90)
			(size 0.5 0.5)
			(layers "F.Cu" "F.Mask" "F.Paste")
			(net 1 "GND")
			(pinfunction "GND")
			(pintype "passive")
			(solder_mask_margin 0.075)
		)
		(pad "E20" smd circle
			(at 6.5 -8.5 90)
			(size 0.5 0.5)
			(layers "F.Cu" "F.Mask" "F.Paste")
			(net 635 "/FPGA banks HP/SD.CD")
			(pinfunction "IO_L10N_T1U_N7_QBC_AD4N_67")
			(pintype "bidirectional")
			(die_length 12.829)
			(solder_mask_margin 0.075)
		)
		(pad "E21" smd circle
			(at 7.5 -8.5 90)
			(size 0.5 0.5)
			(layers "F.Cu" "F.Mask" "F.Paste")
			(net 409 "/Ethernet/ETH.TXC")
			(pinfunction "IO_L20P_T3L_N2_AD1P_67")
			(pintype "bidirectional")
			(die_length 11.169)
			(solder_mask_margin 0.075)
		)
		(pad "E22" smd circle
			(at 8.5 -8.5 90)
			(size 0.5 0.5)
			(layers "F.Cu" "F.Mask" "F.Paste")
			(net 521 "unconnected-(U34E-IO_T3U_N12_67-PadE22)")
			(pinfunction "IO_T3U_N12_67")
			(pintype "bidirectional+no_connect")
			(die_length 11.166)
			(solder_mask_margin 0.075)
		)
		(pad "E23" smd circle
			(at 9.5 -8.5 90)
			(size 0.5 0.5)
			(layers "F.Cu" "F.Mask" "F.Paste")
			(net 455 "/DDR5 RDIMM/B.DQ26")
			(pinfunction "IO_L20N_T3L_N3_AD1N_66")
			(pintype "bidirectional")
			(die_length 13.567)
			(solder_mask_margin 0.075)
		)
		(pad "E24" smd circle
			(at 10.5 -8.5 90)
			(size 0.5 0.5)
			(layers "F.Cu" "F.Mask" "F.Paste")
			(net 687 "VDDQ")
			(pinfunction "VCCO_66")
			(pintype "power_in")
			(solder_mask_margin 0.075)
		)
		(pad "E25" smd circle
			(at 11.5 -8.5 90)
			(size 0.5 0.5)
			(layers "F.Cu" "F.Mask" "F.Paste")
			(net 156 "/DDR5 RDIMM/B.DQS3_P")
			(pinfunction "IO_L19P_T3L_N0_DBC_AD9P_66")
			(pintype "bidirectional")
			(die_length 16.51)
			(solder_mask_margin 0.075)
		)
		(pad "E26" smd circle
			(at 12.5 -8.5 90)
			(size 0.5 0.5)
			(layers "F.Cu" "F.Mask" "F.Paste")
			(net 161 "/DDR5 RDIMM/B.DQS3_N")
			(pinfunction "IO_L19N_T3L_N1_DBC_AD9N_66")
			(pintype "bidirectional")
			(die_length 16.508)
			(solder_mask_margin 0.075)
		)
		(pad "F1" smd circle
			(at -12.5 -7.5 90)
			(size 0.5 0.5)
			(layers "F.Cu" "F.Mask" "F.Paste")
			(net 522 "unconnected-(U34K-MGTYRXN3_226-PadF1)")
			(pinfunction "MGTYRXN3_226")
			(pintype "input+no_connect")
			(die_length 12.078)
			(solder_mask_margin 0.075)
		)
		(pad "F2" smd circle
			(at -11.5 -7.5 90)
			(size 0.5 0.5)
			(layers "F.Cu" "F.Mask" "F.Paste")
			(net 523 "unconnected-(U34K-MGTYRXP3_226-PadF2)")
			(pinfunction "MGTYRXP3_226")
			(pintype "input+no_connect")
			(die_length 12.056)
			(solder_mask_margin 0.075)
		)
		(pad "F3" smd circle
			(at -10.5 -7.5 90)
			(size 0.5 0.5)
			(layers "F.Cu" "F.Mask" "F.Paste")
			(net 1 "GND")
			(pinfunction "GND")
			(pintype "passive")
			(solder_mask_margin 0.075)
		)
		(pad "F4" smd circle
			(at -9.5 -7.5 90)
			(size 0.5 0.5)
			(layers "F.Cu" "F.Mask" "F.Paste")
			(net 1 "GND")
			(pinfunction "GND")
			(pintype "passive")
			(solder_mask_margin 0.075)
		)
		(pad "F5" smd circle
			(at -8.5 -7.5 90)
			(size 0.5 0.5)
			(layers "F.Cu" "F.Mask" "F.Paste")
			(net 172 "+1V2_MGTAVTT")
			(pinfunction "MGTAVTT_R")
			(pintype "passive")
			(solder_mask_margin 0.075)
		)
		(pad "F6" smd circle
			(at -7.5 -7.5 90)
			(size 0.5 0.5)
			(layers "F.Cu" "F.Mask" "F.Paste")
			(net 524 "unconnected-(U34L-NC-PadF6)")
			(pinfunction "NC")
			(pintype "no_connect")
			(solder_mask_margin 0.075)
		)
		(pad "F7" smd circle
			(at -6.5 -7.5 90)
			(size 0.5 0.5)
			(layers "F.Cu" "F.Mask" "F.Paste")
			(net 525 "unconnected-(U34L-NC-PadF7)")
			(pinfunction "NC")
			(pintype "no_connect")
			(solder_mask_margin 0.075)
		)
		(pad "F8" smd circle
			(at -5.5 -7.5 90)
			(size 0.5 0.5)
			(layers "F.Cu" "F.Mask" "F.Paste")
			(net 1 "GND")
			(pinfunction "GND")
			(pintype "passive")
			(solder_mask_margin 0.075)
		)
		(pad "F9" smd circle
			(at -4.5 -7.5 90)
			(size 0.5 0.5)
			(layers "F.Cu" "F.Mask" "F.Paste")
			(net 378 "/Debug FTDI + VNA/UART1.RX")
			(pinfunction "IO_L6N_HDGC_AD6N_86")
			(pintype "bidirectional")
			(die_length 16.849)
			(solder_mask_margin 0.075)
		)
		(pad "F10" smd circle
			(at -3.5 -7.5 90)
			(size 0.5 0.5)
			(layers "F.Cu" "F.Mask" "F.Paste")
			(net 377 "/Debug FTDI + VNA/UART1.TX")
			(pinfunction "IO_L6P_HDGC_AD6P_86")
			(pintype "bidirectional")
			(die_length 16.648)
			(solder_mask_margin 0.075)
		)
		(pad "F11" smd circle
			(at -2.5 -7.5 90)
			(size 0.5 0.5)
			(layers "F.Cu" "F.Mask" "F.Paste")
			(net 1 "GND")
			(pinfunction "GND")
			(pintype "passive")
			(solder_mask_margin 0.075)
		)
		(pad "F12" smd circle
			(at -1.5 -7.5 90)
			(size 0.5 0.5)
			(layers "F.Cu" "F.Mask" "F.Paste")
			(net 771 "/FPGA banks HD/FPGA_I3C.SCL")
			(pinfunction "IO_L5N_HDGC_87")
			(pintype "bidirectional")
			(die_length 13.397)
			(solder_mask_margin 0.075)
		)
		(pad "F13" smd circle
			(at -0.5 -7.5 90)
			(size 0.5 0.5)
			(layers "F.Cu" "F.Mask" "F.Paste")
			(net 778 "~{FPGA_I3C_EXT_PU}")
			(pinfunction "IO_L6N_HDGC_87")
			(pintype "bidirectional")
			(die_length 12.316)
			(solder_mask_margin 0.075)
		)
		(pad "F14" smd circle
			(at 0.5 -7.5 90)
			(size 0.5 0.5)
			(layers "F.Cu" "F.Mask" "F.Paste")
			(net 507 "HDMI_IN_CD")
			(pinfunction "IO_L6P_HDGC_87")
			(pintype "bidirectional")
			(die_length 12.245)
			(solder_mask_margin 0.075)
		)
		(pad "F15" smd circle
			(at 1.5 -7.5 90)
			(size 0.5 0.5)
			(layers "F.Cu" "F.Mask" "F.Paste")
			(net 623 "/FPGA banks HP/HyperRAM.~{RESET}")
			(pinfunction "IO_L1N_T0L_N1_DBC_67")
			(pintype "bidirectional")
			(die_length 16.19)
			(solder_mask_margin 0.075)
		)
		(pad "F16" smd circle
			(at 2.5 -7.5 90)
			(size 0.5 0.5)
			(layers "F.Cu" "F.Mask" "F.Paste")
			(net 1 "GND")
			(pinfunction "GND")
			(pintype "passive")
			(solder_mask_margin 0.075)
		)
		(pad "F17" smd circle
			(at 3.5 -7.5 90)
			(size 0.5 0.5)
			(layers "F.Cu" "F.Mask" "F.Paste")
			(net 601 "/FPGA banks HP/VRP_67")
			(pinfunction "IO_T0U_N12_VRP_67")
			(pintype "bidirectional")
			(die_length 13.09)
			(solder_mask_margin 0.075)
		)
		(pad "F18" smd circle
			(at 4.5 -7.5 90)
			(size 0.5 0.5)
			(layers "F.Cu" "F.Mask" "F.Paste")
			(net 636 "/FPGA banks HP/SD.CLK")
			(pinfunction "IO_L8P_T1L_N2_AD5P_67")
			(pintype "bidirectional")
			(die_length 16)
			(solder_mask_margin 0.075)
		)
		(pad "F19" smd circle
			(at 5.5 -7.5 90)
			(size 0.5 0.5)
			(layers "F.Cu" "F.Mask" "F.Paste")
			(net 640 "/FPGA banks HP/SD.DAT2")
			(pinfunction "IO_L8N_T1L_N3_AD5N_67")
			(pintype "bidirectional")
			(die_length 14.855)
			(solder_mask_margin 0.075)
		)
		(pad "F20" smd circle
			(at 6.5 -7.5 90)
			(size 0.5 0.5)
			(layers "F.Cu" "F.Mask" "F.Paste")
			(net 641 "/FPGA banks HP/SD.DAT3")
			(pinfunction "IO_L10P_T1U_N6_QBC_AD4P_67")
			(pintype "bidirectional")
			(die_length 12.765)
			(solder_mask_margin 0.075)
		)
		(pad "F21" smd circle
			(at 7.5 -7.5 90)
			(size 0.5 0.5)
			(layers "F.Cu" "F.Mask" "F.Paste")
			(net 1 "GND")
			(pinfunction "GND")
			(pintype "passive")
			(solder_mask_margin 0.075)
		)
		(pad "F22" smd circle
			(at 8.5 -7.5 90)
			(size 0.5 0.5)
			(layers "F.Cu" "F.Mask" "F.Paste")
			(net 529 "unconnected-(U34D-IO_T3U_N12_66-PadF22)")
			(pinfunction "IO_T3U_N12_66")
			(pintype "bidirectional+no_connect")
			(die_length 13.582)
			(solder_mask_margin 0.075)
		)
		(pad "F23" smd circle
			(at 9.5 -7.5 90)
			(size 0.5 0.5)
			(layers "F.Cu" "F.Mask" "F.Paste")
			(net 124 "/DDR5 RDIMM/B.DQ24")
			(pinfunction "IO_L20P_T3L_N2_AD1P_66")
			(pintype "bidirectional")
			(die_length 13.766)
			(solder_mask_margin 0.075)
		)
		(pad "F24" smd circle
			(at 10.5 -7.5 90)
			(size 0.5 0.5)
			(layers "F.Cu" "F.Mask" "F.Paste")
			(net 595 "/DDR5 RDIMM/B.DQS7_P")
			(pinfunction "IO_L16P_T2U_N6_QBC_AD3P_66")
			(pintype "bidirectional")
			(die_length 13.568)
			(solder_mask_margin 0.075)
		)
		(pad "F25" smd circle
			(at 11.5 -7.5 90)
			(size 0.5 0.5)
			(layers "F.Cu" "F.Mask" "F.Paste")
			(net 594 "/DDR5 RDIMM/B.DQS7_N")
			(pinfunction "IO_L16N_T2U_N7_QBC_AD3N_66")
			(pintype "bidirectional")
			(die_length 13.629)
			(solder_mask_margin 0.075)
		)
		(pad "F26" smd circle
			(at 12.5 -7.5 90)
			(size 0.5 0.5)
			(layers "F.Cu" "F.Mask" "F.Paste")
			(net 1 "GND")
			(pinfunction "GND")
			(pintype "passive")
			(solder_mask_margin 0.075)
		)
		(pad "G1" smd circle
			(at -12.5 -6.5 90)
			(size 0.5 0.5)
			(layers "F.Cu" "F.Mask" "F.Paste")
			(net 1 "GND")
			(pinfunction "GND")
			(pintype "passive")
			(solder_mask_margin 0.075)
		)
		(pad "G2" smd circle
			(at -11.5 -6.5 90)
			(size 0.5 0.5)
			(layers "F.Cu" "F.Mask" "F.Paste")
			(net 1 "GND")
			(pinfunction "GND")
			(pintype "passive")
			(solder_mask_margin 0.075)
		)
		(pad "G3" smd circle
			(at -10.5 -6.5 90)
			(size 0.5 0.5)
			(layers "F.Cu" "F.Mask" "F.Paste")
			(net 1 "GND")
			(pinfunction "GND")
			(pintype "passive")
			(solder_mask_margin 0.075)
		)
		(pad "G4" smd circle
			(at -9.5 -6.5 90)
			(size 0.5 0.5)
			(layers "F.Cu" "F.Mask" "F.Paste")
			(net 384 "/FPGA MGT Interface/HDMI_FPGA.TX_CLK_N")
			(pinfunction "MGTYTXN3_226")
			(pintype "output")
			(die_length 8.69)
			(solder_mask_margin 0.075)
		)
		(pad "G5" smd circle
			(at -8.5 -6.5 90)
			(size 0.5 0.5)
			(layers "F.Cu" "F.Mask" "F.Paste")
			(net 382 "/FPGA MGT Interface/HDMI_FPGA.TX_CLK_P")
			(pinfunction "MGTYTXP3_226")
			(pintype "output")
			(die_length 8.707)
			(solder_mask_margin 0.075)
		)
		(pad "G6" smd circle
			(at -7.5 -6.5 90)
			(size 0.5 0.5)
			(layers "F.Cu" "F.Mask" "F.Paste")
			(net 1 "GND")
			(pinfunction "GND")
			(pintype "passive")
			(solder_mask_margin 0.075)
		)
		(pad "G7" smd circle
			(at -6.5 -6.5 90)
			(size 0.5 0.5)
			(layers "F.Cu" "F.Mask" "F.Paste")
			(net 172 "+1V2_MGTAVTT")
			(pinfunction "MGTAVTT_R")
			(pintype "passive")
			(solder_mask_margin 0.075)
		)
		(pad "G8" smd circle
			(at -5.5 -6.5 90)
			(size 0.5 0.5)
			(layers "F.Cu" "F.Mask" "F.Paste")
			(net 1 "GND")
			(pinfunction "GND")
			(pintype "passive")
			(solder_mask_margin 0.075)
		)
		(pad "G9" smd circle
			(at -4.5 -6.5 90)
			(size 0.5 0.5)
			(layers "F.Cu" "F.Mask" "F.Paste")
			(net 374 "/Debug FTDI + VNA/UART0.TX")
			(pinfunction "IO_L5N_HDGC_AD7N_86")
			(pintype "bidirectional")
			(die_length 15.674)
			(solder_mask_margin 0.075)
		)
		(pad "G10" smd circle
			(at -3.5 -6.5 90)
			(size 0.5 0.5)
			(layers "F.Cu" "F.Mask" "F.Paste")
			(net 376 "/Debug FTDI + VNA/UART0.RX")
			(pinfunction "IO_L5P_HDGC_AD7P_86")
			(pintype "bidirectional")
			(die_length 15.718)
			(solder_mask_margin 0.075)
		)
		(pad "G11" smd circle
			(at -2.5 -6.5 90)
			(size 0.5 0.5)
			(layers "F.Cu" "F.Mask" "F.Paste")
			(net 532 "unconnected-(U34G-IO_L4N_AD8N_86-PadG11)")
			(pinfunction "IO_L4N_AD8N_86")
			(pintype "bidirectional+no_connect")
			(die_length 13.832)
			(solder_mask_margin 0.075)
		)
		(pad "G12" smd circle
			(at -1.5 -6.5 90)
			(size 0.5 0.5)
			(layers "F.Cu" "F.Mask" "F.Paste")
			(net 528 "/FPGA banks HD/FPGA_I3C.SDA")
			(pinfunction "IO_L5P_HDGC_87")
			(pintype "bidirectional")
			(die_length 13.4)
			(solder_mask_margin 0.075)
		)
		(pad "G13" smd circle
			(at -0.5 -6.5 90)
			(size 0.5 0.5)
			(layers "F.Cu" "F.Mask" "F.Paste")
			(net 1 "GND")
			(pinfunction "GND")
			(pintype "passive")
			(solder_mask_margin 0.075)
		)
		(pad "G14" smd circle
			(at 0.5 -6.5 90)
			(size 0.5 0.5)
			(layers "F.Cu" "F.Mask" "F.Paste")
			(net 798 "unconnected-(U34H-IO_L3N_AD13N_87-PadG14)")
			(pinfunction "IO_L3N_AD13N_87")
			(pintype "bidirectional+no_connect")
			(die_length 10.216)
			(solder_mask_margin 0.075)
		)
		(pad "G15" smd circle
			(at 1.5 -6.5 90)
			(size 0.5 0.5)
			(layers "F.Cu" "F.Mask" "F.Paste")
			(net 624 "/FPGA banks HP/HyperRAM.RWDS")
			(pinfunction "IO_L1P_T0L_N0_DBC_67")
			(pintype "bidirectional")
			(die_length 16.059)
			(solder_mask_margin 0.075)
		)
		(pad "G16" smd circle
			(at 2.5 -6.5 90)
			(size 0.5 0.5)
			(layers "F.Cu" "F.Mask" "F.Paste")
			(net 621 "/FPGA banks HP/HyperRAM.DQ4")
			(pinfunction "IO_L5N_T0U_N9_AD14N_67")
			(pintype "bidirectional")
			(die_length 13.156)
			(solder_mask_margin 0.075)
		)
		(pad "G17" smd circle
			(at 3.5 -6.5 90)
			(size 0.5 0.5)
			(layers "F.Cu" "F.Mask" "F.Paste")
			(net 610 "/FPGA banks HP/HyperRAM.DQ7")
			(pinfunction "IO_L2N_T0L_N3_67")
			(pintype "bidirectional")
			(die_length 13.048)
			(solder_mask_margin 0.075)
		)
	)
)
